(kicad_pcb
	(version 20260206)
	(generator "pcbnew")
	(generator_version "10.0")
	(general
		(thickness 1.6)
		(legacy_teardrops no)
	)
	(paper "A4")
	(title_block
		(title "dpb — 14545-sa.0730WZS0815.brd")
		(comment 1 "Honey Badger (Wiwynn) / footprints 664-671 of 1066")
	)
	(layers
		(0 "F.Cu" signal "TOP")
		(4 "In1.Cu" signal "L2GND")
		(6 "In2.Cu" signal "L3")
		(8 "In3.Cu" signal "L4VCC")
		(10 "In4.Cu" signal "L5VCC")
		(12 "In5.Cu" signal "L6")
		(14 "In6.Cu" signal "L7GND")
		(2 "B.Cu" signal "BOTTOM")
		(9 "F.Adhes" user "F.Adhesive")
		(11 "B.Adhes" user "B.Adhesive")
		(13 "F.Paste" user "Package Geometry/Pastemask Top")
		(15 "B.Paste" user "Package Geometry/Pastemask Bottom")
		(5 "F.SilkS" user "Ref Des/Silkscreen Top")
		(7 "B.SilkS" user "Ref Des/Silkscreen Bottom")
		(1 "F.Mask" user "Board Geometry/Soldermask Top")
		(3 "B.Mask" user "Board Geometry/Soldermask Bottom")
		(17 "Dwgs.User" user "User.Drawings")
		(19 "Cmts.User" user "User.Comments")
		(21 "Eco1.User" user "User.Eco1")
		(23 "Eco2.User" user "User.Eco2")
		(25 "Edge.Cuts" user "Board Geometry/Outline")
		(27 "Margin" user)
		(31 "F.CrtYd" user "Package Geometry/Place Bound Top")
		(29 "B.CrtYd" user "Package Geometry/Place Bound Bottom")
		(35 "F.Fab" user "Ref Des/Assembly Top")
		(33 "B.Fab" user "Ref Des/Assembly Bottom")
	)
	(footprint ""
		(layer "F.Cu")
		(at 176.161446 -457.234036)
		(property "Reference" "C361"
			(at 0 0 0)
			(layer "F.SilkS")
			(hide yes)
			(effects
				(font
					(size 1.27 1.27)
				)
			)
		)
		(property "Value" "SCD1U16V2KX-3GP"
			(at 1.1811 -2.7051 0)
			(unlocked yes)
			(layer "F.Fab")
			(hide yes)
			(effects
				(font
					(size 1.016 1.016)
					(thickness 0.1524)
				)
			)
		)
		(property "Device Type" "C402H22"
			(at 1.1811 -4.2291 0)
			(unlocked yes)
			(layer "F.Fab")
			(hide yes)
			(effects
				(font
					(size 1.016 1.016)
					(thickness 0.1524)
				)
			)
		)
		(duplicate_pad_numbers_are_jumpers no)
		(fp_rect
			(start -0.4318 0.9525)
			(end 0.4318 -0.9525)
			(stroke
				(width 0)
				(type default)
			)
			(fill no)
			(layer "F.CrtYd")
		)
		(fp_rect
			(start -0.4318 0.9525)
			(end 0.4318 -0.9525)
			(stroke
				(width 0)
				(type default)
			)
			(fill no)
			(layer "F.Fab")
		)
		(pad "1" smd custom
			(at 0 -0.4445)
			(size 0.1524 0.1524)
			(layers "F.Cu" "F.Mask" "F.Paste")
			(net "P5VC_SENSE")
			(options
				(clearance outline)
				(anchor circle)
			)
			(primitives
				(gr_poly
					(pts
						(arc
							(start 0.3048 -0.2032)
							(mid 0.275042 -0.275042)
							(end 0.2032 -0.3048)
						)
						(arc
							(start -0.2032 -0.3048)
							(mid -0.275042 -0.275042)
							(end -0.3048 -0.2032)
						)
						(arc
							(start -0.3048 0.2032)
							(mid -0.275042 0.275042)
							(end -0.2032 0.3048)
						)
						(arc
							(start 0.2032 0.3048)
							(mid 0.275042 0.275042)
							(end 0.3048 0.2032)
						)
					)
					(width 0)
					(fill yes)
				)
			)
		)
		(pad "2" smd custom
			(at 0 0.4445)
			(size 0.1524 0.1524)
			(layers "F.Cu" "F.Mask" "F.Paste")
			(net "GND")
			(options
				(clearance outline)
				(anchor circle)
			)
			(primitives
				(gr_poly
					(pts
						(arc
							(start 0.3048 -0.2032)
							(mid 0.275042 -0.275042)
							(end 0.2032 -0.3048)
						)
						(arc
							(start -0.2032 -0.3048)
							(mid -0.275042 -0.275042)
							(end -0.3048 -0.2032)
						)
						(arc
							(start -0.3048 0.2032)
							(mid -0.275042 0.275042)
							(end -0.2032 0.3048)
						)
						(arc
							(start 0.2032 0.3048)
							(mid 0.275042 0.275042)
							(end 0.3048 0.2032)
						)
					)
					(width 0)
					(fill yes)
				)
			)
		)
	)
	(footprint ""
		(layer "F.Cu")
		(at 64.389 -485.013)
		(property "Reference" "C369"
			(at 0 0 0)
			(layer "F.SilkS")
			(hide yes)
			(effects
				(font
					(size 1.27 1.27)
				)
			)
		)
		(property "Value" "SCD033U25V2KX-GP"
			(at 1.1811 -2.7051 0)
			(unlocked yes)
			(layer "F.Fab")
			(hide yes)
			(effects
				(font
					(size 1.016 1.016)
					(thickness 0.1524)
				)
			)
		)
		(property "Device Type" "C402H22"
			(at 1.1811 -4.2291 0)
			(unlocked yes)
			(layer "F.Fab")
			(hide yes)
			(effects
				(font
					(size 1.016 1.016)
					(thickness 0.1524)
				)
			)
		)
		(duplicate_pad_numbers_are_jumpers no)
		(fp_rect
			(start -0.4318 0.9525)
			(end 0.4318 -0.9525)
			(stroke
				(width 0)
				(type default)
			)
			(fill no)
			(layer "F.CrtYd")
		)
		(fp_rect
			(start -0.4318 0.9525)
			(end 0.4318 -0.9525)
			(stroke
				(width 0)
				(type default)
			)
			(fill no)
			(layer "F.Fab")
		)
		(pad "1" smd custom
			(at 0 -0.4445)
			(size 0.1524 0.1524)
			(layers "F.Cu" "F.Mask" "F.Paste")
			(net "SW_HDD5_P")
			(options
				(clearance outline)
				(anchor circle)
			)
			(primitives
				(gr_poly
					(pts
						(arc
							(start 0.3048 -0.2032)
							(mid 0.275042 -0.275042)
							(end 0.2032 -0.3048)
						)
						(arc
							(start -0.2032 -0.3048)
							(mid -0.275042 -0.275042)
							(end -0.3048 -0.2032)
						)
						(arc
							(start -0.3048 0.2032)
							(mid -0.275042 0.275042)
							(end -0.2032 0.3048)
						)
						(arc
							(start 0.2032 0.3048)
							(mid 0.275042 0.275042)
							(end 0.3048 0.2032)
						)
					)
					(width 0)
					(fill yes)
				)
			)
		)
		(pad "2" smd custom
			(at 0 0.4445)
			(size 0.1524 0.1524)
			(layers "F.Cu" "F.Mask" "F.Paste")
			(net "GND")
			(options
				(clearance outline)
				(anchor circle)
			)
			(primitives
				(gr_poly
					(pts
						(arc
							(start 0.3048 -0.2032)
							(mid 0.275042 -0.275042)
							(end 0.2032 -0.3048)
						)
						(arc
							(start -0.2032 -0.3048)
							(mid -0.275042 -0.275042)
							(end -0.3048 -0.2032)
						)
						(arc
							(start -0.3048 0.2032)
							(mid -0.275042 0.275042)
							(end -0.2032 0.3048)
						)
						(arc
							(start 0.2032 0.3048)
							(mid 0.275042 0.275042)
							(end 0.3048 0.2032)
						)
					)
					(width 0)
					(fill yes)
				)
			)
		)
	)
	(footprint ""
		(layer "F.Cu")
		(at 195.326 -498.475)
		(property "Reference" "C379"
			(at 0 0 0)
			(layer "F.SilkS")
			(hide yes)
			(effects
				(font
					(size 1.27 1.27)
				)
			)
		)
		(property "Value" "SCD033U25V2KX-GP"
			(at 1.1811 -2.7051 0)
			(unlocked yes)
			(layer "F.Fab")
			(hide yes)
			(effects
				(font
					(size 1.016 1.016)
					(thickness 0.1524)
				)
			)
		)
		(property "Device Type" "C402H22"
			(at 1.1811 -4.2291 0)
			(unlocked yes)
			(layer "F.Fab")
			(hide yes)
			(effects
				(font
					(size 1.016 1.016)
					(thickness 0.1524)
				)
			)
		)
		(duplicate_pad_numbers_are_jumpers no)
		(fp_rect
			(start -0.4318 0.9525)
			(end 0.4318 -0.9525)
			(stroke
				(width 0)
				(type default)
			)
			(fill no)
			(layer "F.CrtYd")
		)
		(fp_rect
			(start -0.4318 0.9525)
			(end 0.4318 -0.9525)
			(stroke
				(width 0)
				(type default)
			)
			(fill no)
			(layer "F.Fab")
		)
		(pad "1" smd custom
			(at 0 -0.4445)
			(size 0.1524 0.1524)
			(layers "F.Cu" "F.Mask" "F.Paste")
			(net "P12V")
			(options
				(clearance outline)
				(anchor circle)
			)
			(primitives
				(gr_poly
					(pts
						(arc
							(start 0.3048 -0.2032)
							(mid 0.275042 -0.275042)
							(end 0.2032 -0.3048)
						)
						(arc
							(start -0.2032 -0.3048)
							(mid -0.275042 -0.275042)
							(end -0.3048 -0.2032)
						)
						(arc
							(start -0.3048 0.2032)
							(mid -0.275042 0.275042)
							(end -0.2032 0.3048)
						)
						(arc
							(start 0.2032 0.3048)
							(mid 0.275042 0.275042)
							(end 0.3048 0.2032)
						)
					)
					(width 0)
					(fill yes)
				)
			)
		)
		(pad "2" smd custom
			(at 0 0.4445)
			(size 0.1524 0.1524)
			(layers "F.Cu" "F.Mask" "F.Paste")
			(net "SW_HDD0_N")
			(options
				(clearance outline)
				(anchor circle)
			)
			(primitives
				(gr_poly
					(pts
						(arc
							(start 0.3048 -0.2032)
							(mid 0.275042 -0.275042)
							(end 0.2032 -0.3048)
						)
						(arc
							(start -0.2032 -0.3048)
							(mid -0.275042 -0.275042)
							(end -0.3048 -0.2032)
						)
						(arc
							(start -0.3048 0.2032)
							(mid -0.275042 0.275042)
							(end -0.2032 0.3048)
						)
						(arc
							(start 0.2032 0.3048)
							(mid 0.275042 0.275042)
							(end 0.3048 0.2032)
						)
					)
					(width 0)
					(fill yes)
				)
			)
		)
	)
	(footprint ""
		(layer "F.Cu")
		(at 55.955692 -87.912956 180)
		(property "Reference" "C258"
			(at 0 0 180)
			(layer "F.SilkS")
			(hide yes)
			(effects
				(font
					(size 1.27 1.27)
				)
			)
		)
		(property "Value" "SC10U25V6KX-1GP"
			(at -0.0762 -5.1308 180)
			(unlocked yes)
			(layer "F.Fab")
			(hide yes)
			(effects
				(font
					(size 1.016 1.016)
					(thickness 0.1524)
				)
			)
		)
		(property "Device Type" "C1206H71"
			(at -0.127 -6.6548 180)
			(unlocked yes)
			(layer "F.Fab")
			(hide yes)
			(effects
				(font
					(size 1.016 1.016)
					(thickness 0.1524)
				)
			)
		)
		(duplicate_pad_numbers_are_jumpers no)
		(fp_line
			(start 1.016 2.2352)
			(end -1.016 2.2352)
			(stroke
				(width 0.1524)
				(type default)
			)
			(layer "F.SilkS")
		)
		(fp_line
			(start 1.016 0.8382)
			(end 1.016 2.2352)
			(stroke
				(width 0.1524)
				(type default)
			)
			(layer "F.SilkS")
		)
		(fp_line
			(start 1.016 -2.2352)
			(end 1.016 -0.8382)
			(stroke
				(width 0.1524)
				(type default)
			)
			(layer "F.SilkS")
		)
		(fp_line
			(start -1.016 2.2352)
			(end -1.016 0.8382)
			(stroke
				(width 0.1524)
				(type default)
			)
			(layer "F.SilkS")
		)
		(fp_line
			(start -1.016 -0.8382)
			(end -1.016 -2.2352)
			(stroke
				(width 0.1524)
				(type default)
			)
			(layer "F.SilkS")
		)
		(fp_line
			(start -1.016 -2.2352)
			(end 1.016 -2.2352)
			(stroke
				(width 0.1524)
				(type default)
			)
			(layer "F.SilkS")
		)
		(fp_rect
			(start -1.0922 2.3114)
			(end 1.0922 -2.3114)
			(stroke
				(width 0)
				(type default)
			)
			(fill no)
			(layer "F.CrtYd")
		)
		(fp_poly
			(pts
				(xy 1.0922 -2.3114) (xy 1.0922 2.3114) (xy -1.0922 2.3114) (xy -1.0922 -2.3114)
			)
			(stroke
				(width 0)
				(type default)
			)
			(fill no)
			(layer "F.Fab")
		)
		(pad "1" smd rect
			(at 0 -1.397 180)
			(size 1.651 1.27)
			(layers "F.Cu" "F.Mask" "F.Paste")
			(net "P12V_HDD9")
		)
		(pad "2" smd rect
			(at 0 1.397 180)
			(size 1.651 1.27)
			(layers "F.Cu" "F.Mask" "F.Paste")
			(net "GND")
		)
	)
	(footprint ""
		(layer "F.Cu")
		(at 202.945746 -84.3407 -90)
		(property "Reference" "R439"
			(at 0 0 270)
			(layer "F.SilkS")
			(hide yes)
			(effects
				(font
					(size 1.27 1.27)
				)
			)
		)
		(property "Value" "4K7R2J-2-GP"
			(at 0.064008 -3.993896 270)
			(unlocked yes)
			(layer "F.Fab")
			(hide yes)
			(effects
				(font
					(size 1.016 1.016)
					(thickness 0.1524)
				)
			)
		)
		(property "Device Type" "R402H16"
			(at 0.064008 -5.517896 270)
			(unlocked yes)
			(layer "F.Fab")
			(hide yes)
			(effects
				(font
					(size 1.016 1.016)
					(thickness 0.1524)
				)
			)
		)
		(duplicate_pad_numbers_are_jumpers no)
		(fp_line
			(start -0.508 -0.9398)
			(end -0.508 0.9398)
			(stroke
				(width 0.1524)
				(type default)
			)
			(layer "F.SilkS")
		)
		(fp_line
			(start 0.508 -0.9398)
			(end -0.508 -0.9398)
			(stroke
				(width 0.1524)
				(type default)
			)
			(layer "F.SilkS")
		)
		(fp_rect
			(start -0.508 0.9398)
			(end 0.508 -0.9398)
			(stroke
				(width 0)
				(type default)
			)
			(fill no)
			(layer "F.CrtYd")
		)
		(fp_rect
			(start -0.508 0.9398)
			(end 0.508 -0.9398)
			(stroke
				(width 0)
				(type default)
			)
			(fill no)
			(layer "F.Fab")
		)
		(pad "1" smd custom
			(at 0 -0.4445 270)
			(size 0.1397 0.1397)
			(layers "F.Cu" "F.Mask" "F.Paste")
			(net "P3V3")
			(options
				(clearance outline)
				(anchor circle)
			)
			(primitives
				(gr_poly
					(pts
						(arc
							(start -0.1778 -0.2794)
							(mid -0.249642 -0.249642)
							(end -0.2794 -0.1778)
						)
						(arc
							(start -0.2794 0.1778)
							(mid -0.249642 0.249642)
							(end -0.1778 0.2794)
						)
						(arc
							(start 0.1778 0.2794)
							(mid 0.249642 0.249642)
							(end 0.2794 0.1778)
						)
						(arc
							(start 0.2794 -0.1778)
							(mid 0.249642 -0.249642)
							(end 0.1778 -0.2794)
						)
					)
					(width 0)
					(fill yes)
				)
			)
		)
		(pad "2" smd custom
			(at 0 0.4445 270)
			(size 0.1397 0.1397)
			(layers "F.Cu" "F.Mask" "F.Paste")
			(net "SAS2X28_B_HDD4_FLT")
			(options
				(clearance outline)
				(anchor circle)
			)
			(primitives
				(gr_poly
					(pts
						(arc
							(start -0.1778 -0.2794)
							(mid -0.249642 -0.249642)
							(end -0.2794 -0.1778)
						)
						(arc
							(start -0.2794 0.1778)
							(mid -0.249642 0.249642)
							(end -0.1778 0.2794)
						)
						(arc
							(start 0.1778 0.2794)
							(mid 0.249642 0.249642)
							(end 0.2794 0.1778)
						)
						(arc
							(start 0.2794 -0.1778)
							(mid 0.249642 -0.249642)
							(end 0.1778 -0.2794)
						)
					)
					(width 0)
					(fill yes)
				)
			)
		)
	)
	(footprint ""
		(layer "F.Cu")
		(at 46.006004 -20.936712 90)
		(property "Reference" "PR20"
			(at 0 0 90)
			(layer "F.SilkS")
			(hide yes)
			(effects
				(font
					(size 1.27 1.27)
				)
			)
		)
		(property "Value" "3D01R2F-GP"
			(at 0.064008 -3.993896 90)
			(unlocked yes)
			(layer "F.Fab")
			(hide yes)
			(effects
				(font
					(size 1.016 1.016)
					(thickness 0.1524)
				)
			)
		)
		(property "Device Type" "R402H16"
			(at 0.064008 -5.517896 90)
			(unlocked yes)
			(layer "F.Fab")
			(hide yes)
			(effects
				(font
					(size 1.016 1.016)
					(thickness 0.1524)
				)
			)
		)
		(duplicate_pad_numbers_are_jumpers no)
		(fp_line
			(start 0.508 -0.9398)
			(end -0.508 -0.9398)
			(stroke
				(width 0.1524)
				(type default)
			)
			(layer "F.SilkS")
		)
		(fp_line
			(start -0.508 -0.9398)
			(end -0.508 0.9398)
			(stroke
				(width 0.1524)
				(type default)
			)
			(layer "F.SilkS")
		)
		(fp_rect
			(start -0.508 0.9398)
			(end 0.508 -0.9398)
			(stroke
				(width 0)
				(type default)
			)
			(fill no)
			(layer "F.CrtYd")
		)
		(fp_rect
			(start -0.508 0.9398)
			(end 0.508 -0.9398)
			(stroke
				(width 0)
				(type default)
			)
			(fill no)
			(layer "F.Fab")
		)
		(pad "1" smd custom
			(at 0 -0.4445 90)
			(size 0.1397 0.1397)
			(layers "F.Cu" "F.Mask" "F.Paste")
			(net "GND")
			(options
				(clearance outline)
				(anchor circle)
			)
			(primitives
				(gr_poly
					(pts
						(arc
							(start -0.1778 -0.2794)
							(mid -0.249642 -0.249642)
							(end -0.2794 -0.1778)
						)
						(arc
							(start -0.2794 0.1778)
							(mid -0.249642 0.249642)
							(end -0.1778 0.2794)
						)
						(arc
							(start 0.1778 0.2794)
							(mid 0.249642 0.249642)
							(end 0.2794 0.1778)
						)
						(arc
							(start 0.2794 -0.1778)
							(mid 0.249642 -0.249642)
							(end 0.1778 -0.2794)
						)
					)
					(width 0)
					(fill yes)
				)
			)
		)
		(pad "2" smd custom
			(at 0 0.4445 90)
			(size 0.1397 0.1397)
			(layers "F.Cu" "F.Mask" "F.Paste")
			(net "P5VB_SNB")
			(options
				(clearance outline)
				(anchor circle)
			)
			(primitives
				(gr_poly
					(pts
						(arc
							(start -0.1778 -0.2794)
							(mid -0.249642 -0.249642)
							(end -0.2794 -0.1778)
						)
						(arc
							(start -0.2794 0.1778)
							(mid -0.249642 0.249642)
							(end -0.1778 0.2794)
						)
						(arc
							(start 0.1778 0.2794)
							(mid 0.249642 0.249642)
							(end 0.2794 0.1778)
						)
						(arc
							(start 0.2794 -0.1778)
							(mid 0.249642 -0.249642)
							(end 0.1778 -0.2794)
						)
					)
					(width 0)
					(fill yes)
				)
			)
		)
	)
	(footprint ""
		(layer "F.Cu")
		(at 28.828746 -498.8687 180)
		(property "Reference" "PL5"
			(at 0 0 180)
			(layer "F.SilkS")
			(hide yes)
			(effects
				(font
					(size 1.27 1.27)
				)
			)
		)
		(property "Value" "BLM41PG600-GP"
			(at -3.690874 -7.441184 180)
			(unlocked yes)
			(layer "F.Fab")
			(hide yes)
			(effects
				(font
					(size 1.016 1.016)
					(thickness 0.1524)
				)
			)
		)
		(property "Device Type" "L451616H71"
			(at -3.690874 -5.917184 180)
			(unlocked yes)
			(layer "F.Fab")
			(hide yes)
			(effects
				(font
					(size 1.016 1.016)
					(thickness 0.1524)
				)
			)
		)
		(duplicate_pad_numbers_are_jumpers no)
		(fp_line
			(start 2.8702 1.2954)
			(end 2.8702 -1.2954)
			(stroke
				(width 0.1524)
				(type default)
			)
			(layer "F.SilkS")
		)
		(fp_line
			(start 2.8702 1.2954)
			(end 2.8702 -1.2954)
			(stroke
				(width 0.1524)
				(type default)
			)
			(layer "F.SilkS")
		)
		(fp_line
			(start 2.8702 -1.2954)
			(end -2.8702 -1.2954)
			(stroke
				(width 0.1524)
				(type default)
			)
			(layer "F.SilkS")
		)
		(fp_line
			(start 2.8702 -1.2954)
			(end -2.8702 -1.2954)
			(stroke
				(width 0.1524)
				(type default)
			)
			(layer "F.SilkS")
		)
		(fp_line
			(start -2.8702 1.2954)
			(end 2.8702 1.2954)
			(stroke
				(width 0.1524)
				(type default)
			)
			(layer "F.SilkS")
		)
		(fp_line
			(start -2.8702 1.2954)
			(end 2.8702 1.2954)
			(stroke
				(width 0.1524)
				(type default)
			)
			(layer "F.SilkS")
		)
		(fp_line
			(start -2.8702 -1.2954)
			(end -2.8702 1.2954)
			(stroke
				(width 0.1524)
				(type default)
			)
			(layer "F.SilkS")
		)
		(fp_line
			(start -2.8702 -1.2954)
			(end -2.8702 1.2954)
			(stroke
				(width 0.1524)
				(type default)
			)
			(layer "F.SilkS")
		)
		(fp_poly
			(pts
				(xy -2.8702 1.2954) (xy 2.8702 1.2954) (xy 2.8702 -1.2954) (xy -2.8702 -1.2954)
			)
			(stroke
				(width 0)
				(type default)
			)
			(fill no)
			(layer "F.CrtYd")
		)
		(fp_poly
			(pts
				(xy -2.8702 1.2954) (xy 2.8702 1.2954) (xy 2.8702 -1.2954) (xy -2.8702 -1.2954)
			)
			(stroke
				(width 0)
				(type default)
			)
			(fill no)
			(layer "F.Fab")
		)
		(pad "1" smd rect
			(at -1.9685 0 180)
			(size 1.3716 1.8796)
			(layers "F.Cu" "F.Mask" "F.Paste")
			(net "P12V")
		)
		(pad "2" smd rect
			(at 1.9685 0 180)
			(size 1.3716 1.8796)
			(layers "F.Cu" "F.Mask" "F.Paste")
			(net "P5VC_12VIN")
		)
	)
	(footprint ""
		(layer "F.Cu")
		(at 57.4675 -274.955 90)
		(property "Reference" "R384"
			(at 0 0 90)
			(layer "F.SilkS")
			(hide yes)
			(effects
				(font
					(size 1.27 1.27)
				)
			)
		)
		(property "Value" "0R2J-2-GP"
			(at 0.064008 -3.993896 90)
			(unlocked yes)
			(layer "F.Fab")
			(hide yes)
			(effects
				(font
					(size 1.016 1.016)
					(thickness 0.1524)
				)
			)
		)
		(property "Device Type" "R402H16"
			(at 0.064008 -5.517896 90)
			(unlocked yes)
			(layer "F.Fab")
			(hide yes)
			(effects
				(font
					(size 1.016 1.016)
					(thickness 0.1524)
				)
			)
		)
		(duplicate_pad_numbers_are_jumpers no)
		(fp_line
			(start 0.508 -0.9398)
			(end -0.508 -0.9398)
			(stroke
				(width 0.1524)
				(type default)
			)
			(layer "F.SilkS")
		)
		(fp_line
			(start -0.508 -0.9398)
			(end -0.508 0.9398)
			(stroke
				(width 0.1524)
				(type default)
			)
			(layer "F.SilkS")
		)
		(fp_rect
			(start -0.508 0.9398)
			(end 0.508 -0.9398)
			(stroke
				(width 0)
				(type default)
			)
			(fill no)
			(layer "F.CrtYd")
		)
		(fp_rect
			(start -0.508 0.9398)
			(end 0.508 -0.9398)
			(stroke
				(width 0)
				(type default)
			)
			(fill no)
			(layer "F.Fab")
		)
		(pad "1" smd custom
			(at 0 -0.4445 90)
			(size 0.1397 0.1397)
			(layers "F.Cu" "F.Mask" "F.Paste")
			(net "HDD_PRSNT_NET7")
			(options
				(clearance outline)
				(anchor circle)
			)
			(primitives
				(gr_poly
					(pts
						(arc
							(start -0.1778 -0.2794)
							(mid -0.249642 -0.249642)
							(end -0.2794 -0.1778)
						)
						(arc
							(start -0.2794 0.1778)
							(mid -0.249642 0.249642)
							(end -0.1778 0.2794)
						)
						(arc
							(start 0.1778 0.2794)
							(mid 0.249642 0.249642)
							(end 0.2794 0.1778)
						)
						(arc
							(start 0.2794 -0.1778)
							(mid 0.249642 -0.249642)
							(end 0.1778 -0.2794)
						)
					)
					(width 0)
					(fill yes)
				)
			)
		)
		(pad "2" smd custom
			(at 0 0.4445 90)
			(size 0.1397 0.1397)
			(layers "F.Cu" "F.Mask" "F.Paste")
			(net "HDD7_LED_B")
			(options
				(clearance outline)
				(anchor circle)
			)
			(primitives
				(gr_poly
					(pts
						(arc
							(start -0.1778 -0.2794)
							(mid -0.249642 -0.249642)
							(end -0.2794 -0.1778)
						)
						(arc
							(start -0.2794 0.1778)
							(mid -0.249642 0.249642)
							(end -0.1778 0.2794)
						)
						(arc
							(start 0.1778 0.2794)
							(mid 0.249642 0.249642)
							(end 0.2794 0.1778)
						)
						(arc
							(start 0.2794 -0.1778)
							(mid 0.249642 -0.249642)
							(end 0.1778 -0.2794)
						)
					)
					(width 0)
					(fill yes)
				)
			)
		)
	)
)
